# S9S_MB_2U (Grand Teton) — schematic netlist excerpt (pin names and nets, part order shuffled) for the footprints in the layout excerpt that follows; sources: Cadence DE-HDL packaged netlist, KiCad conversion of 03242023_DA0F0TMBIJ0_F0T_Motherboard_J_brd_V01_OCP.brd

PR3850  Q_RES  100 1% EMPTY  pkg 0402LF  page 163 : A = P12V_OCP_V3_2 ; B = P12V_OCP_AVIN_PD_2
C1876  Q_CAP  0.1UF 25V 10% X7R  pkg 0402  page 165 : A = P3V3_AUX ; B = GND

(kicad_pcb
	(version 20260206)
	(generator "pcbnew")
	(generator_version "10.0")
	(general
		(thickness 1.6)
		(legacy_teardrops no)
	)
	(paper "A4")
	(title_block
		(title "03242023_DA0F0TMBIJ0_F0T_Motherboard_J_brd_V01_OCP.brd")
		(comment 1 "Grand Teton / footprints 2013-2014 of 6105")
	)
	(layers
		(0 "F.Cu" signal "TOP")
		(4 "In1.Cu" signal "GND")
		(6 "In2.Cu" signal "IN1")
		(8 "In3.Cu" signal "GND1")
		(10 "In4.Cu" signal "IN2")
		(12 "In5.Cu" signal "GND2")
		(14 "In6.Cu" signal "IN3")
		(16 "In7.Cu" signal "GND3")
		(18 "In8.Cu" signal "VCC")
		(20 "In9.Cu" signal "VCC1")
		(22 "In10.Cu" signal "GND4")
		(24 "In11.Cu" signal "IN4")
		(26 "In12.Cu" signal "GND5")
		(28 "In13.Cu" signal "IN5")
		(30 "In14.Cu" signal "GND6")
		(32 "In15.Cu" signal "IN6")
		(34 "In16.Cu" signal "GND7")
		(2 "B.Cu" signal "BOTTOM")
		(9 "F.Adhes" user "F.Adhesive")
		(11 "B.Adhes" user "B.Adhesive")
		(13 "F.Paste" user "Package Geometry/Pastemask Top")
		(15 "B.Paste" user "Package Geometry/Pastemask Bottom")
		(5 "F.SilkS" user "Ref Des/Silkscreen Top")
		(7 "B.SilkS" user "Ref Des/Silkscreen Bottom")
		(1 "F.Mask" user "Board Geometry/Soldermask Top")
		(3 "B.Mask" user "Board Geometry/Soldermask Bottom")
		(17 "Dwgs.User" user "User.Drawings")
		(19 "Cmts.User" user "User.Comments")
		(21 "Eco1.User" user "User.Eco1")
		(23 "Eco2.User" user "User.Eco2")
		(25 "Edge.Cuts" user "Board Geometry/Outline")
		(27 "Margin" user)
		(31 "F.CrtYd" user "Package Geometry/Place Bound Top")
		(29 "B.CrtYd" user "Package Geometry/Place Bound Bottom")
		(35 "F.Fab" user "Ref Des/Assembly Top")
		(33 "B.Fab" user "Ref Des/Assembly Bottom")
	)
	(footprint ""
		(layer "F.Cu")
		(at 16.333724 -76.943204)
		(property "Reference" "C1876"
			(at 0 0 0)
			(layer "F.SilkS")
			(hide yes)
			(effects
				(font
					(size 1.27 1.27)
				)
			)
		)
		(property "Value" ""
			(at 0 0 0)
			(layer "F.Fab")
			(effects
				(font
					(size 1.27 1.27)
				)
			)
		)
		(duplicate_pad_numbers_are_jumpers no)
		(fp_line
			(start -0.7874 -0.4064)
			(end 0.7874 -0.4064)
			(stroke
				(width 0.1524)
				(type default)
			)
			(layer "F.SilkS")
		)
		(fp_line
			(start -0.7874 0.4064)
			(end -0.7874 -0.4064)
			(stroke
				(width 0.1524)
				(type default)
			)
			(layer "F.SilkS")
		)
		(fp_line
			(start 0.7874 -0.4064)
			(end 0.7874 0.4064)
			(stroke
				(width 0.1524)
				(type default)
			)
			(layer "F.SilkS")
		)
		(fp_line
			(start 0.7874 0.4064)
			(end -0.7874 0.4064)
			(stroke
				(width 0.1524)
				(type default)
			)
			(layer "F.SilkS")
		)
		(fp_line
			(start -0.67945 -0.305054)
			(end -0.12065 -0.305054)
			(stroke
				(width 0.1)
				(type default)
			)
			(layer "F.Fab")
		)
		(fp_line
			(start -0.67945 0.3048)
			(end -0.67945 -0.305054)
			(stroke
				(width 0.1)
				(type default)
			)
			(layer "F.Fab")
		)
		(fp_line
			(start -0.12065 -0.305054)
			(end -0.12065 -0.2794)
			(stroke
				(width 0.1)
				(type default)
			)
			(layer "F.Fab")
		)
		(fp_line
			(start -0.12065 -0.2794)
			(end 0.12065 -0.2794)
			(stroke
				(width 0.1)
				(type default)
			)
			(layer "F.Fab")
		)
		(fp_line
			(start -0.12065 0.2794)
			(end -0.12065 0.3048)
			(stroke
				(width 0.1)
				(type default)
			)
			(layer "F.Fab")
		)
		(fp_line
			(start -0.12065 0.3048)
			(end -0.67945 0.3048)
			(stroke
				(width 0.1)
				(type default)
			)
			(layer "F.Fab")
		)
		(fp_line
			(start 0.120396 0.2794)
			(end -0.12065 0.2794)
			(stroke
				(width 0.1)
				(type default)
			)
			(layer "F.Fab")
		)
		(fp_line
			(start 0.120396 0.3048)
			(end 0.120396 0.2794)
			(stroke
				(width 0.1)
				(type default)
			)
			(layer "F.Fab")
		)
		(fp_line
			(start 0.12065 -0.3048)
			(end 0.67945 -0.3048)
			(stroke
				(width 0.1)
				(type default)
			)
			(layer "F.Fab")
		)
		(fp_line
			(start 0.12065 -0.2794)
			(end 0.12065 -0.3048)
			(stroke
				(width 0.1)
				(type default)
			)
			(layer "F.Fab")
		)
		(fp_line
			(start 0.67945 -0.3048)
			(end 0.67945 0.3048)
			(stroke
				(width 0.1)
				(type default)
			)
			(layer "F.Fab")
		)
		(fp_line
			(start 0.67945 0.3048)
			(end 0.120396 0.3048)
			(stroke
				(width 0.1)
				(type default)
			)
			(layer "F.Fab")
		)
		(pad "1" smd circle
			(at -0.40005 0)
			(size 0 0)
			(layers "F.Cu" "F.Mask" "F.Paste")
			(net "P3V3_AUX")
		)
		(pad "2" smd circle
			(at 0.40005 0)
			(size 0 0)
			(layers "F.Cu" "F.Mask" "F.Paste")
			(net "GND")
		)
	)
	(footprint ""
		(layer "F.Cu")
		(at 65.861438 -22.235922 180)
		(property "Reference" "PR3850"
			(at 0 0 180)
			(layer "F.SilkS")
			(hide yes)
			(effects
				(font
					(size 1.27 1.27)
				)
			)
		)
		(property "Value" ""
			(at 0 0 180)
			(layer "F.Fab")
			(effects
				(font
					(size 1.27 1.27)
				)
			)
		)
		(duplicate_pad_numbers_are_jumpers no)
		(fp_line
			(start 0.7874 0.4064)
			(end -0.7874 0.4064)
			(stroke
				(width 0.1524)
				(type default)
			)
			(layer "F.SilkS")
		)
		(fp_line
			(start 0.7874 -0.4064)
			(end 0.7874 0.4064)
			(stroke
				(width 0.1524)
				(type default)
			)
			(layer "F.SilkS")
		)
		(fp_line
			(start -0.7874 0.4064)
			(end -0.7874 -0.4064)
			(stroke
				(width 0.1524)
				(type default)
			)
			(layer "F.SilkS")
		)
		(fp_line
			(start -0.7874 -0.4064)
			(end 0.7874 -0.4064)
			(stroke
				(width 0.1524)
				(type default)
			)
			(layer "F.SilkS")
		)
		(fp_line
			(start 0.67945 0.3048)
			(end 0.120396 0.3048)
			(stroke
				(width 0.1)
				(type default)
			)
			(layer "F.Fab")
		)
		(fp_line
			(start 0.67945 -0.3048)
			(end 0.67945 0.3048)
			(stroke
				(width 0.1)
				(type default)
			)
			(layer "F.Fab")
		)
		(fp_line
			(start 0.12065 -0.2794)
			(end 0.12065 -0.3048)
			(stroke
				(width 0.1)
				(type default)
			)
			(layer "F.Fab")
		)
		(fp_line
			(start 0.12065 -0.3048)
			(end 0.67945 -0.3048)
			(stroke
				(width 0.1)
				(type default)
			)
			(layer "F.Fab")
		)
		(fp_line
			(start 0.120396 0.3048)
			(end 0.120396 0.2794)
			(stroke
				(width 0.1)
				(type default)
			)
			(layer "F.Fab")
		)
		(fp_line
			(start 0.120396 0.2794)
			(end -0.12065 0.2794)
			(stroke
				(width 0.1)
				(type default)
			)
			(layer "F.Fab")
		)
		(fp_line
			(start -0.12065 0.3048)
			(end -0.67945 0.3048)
			(stroke
				(width 0.1)
				(type default)
			)
			(layer "F.Fab")
		)
		(fp_line
			(start -0.12065 0.2794)
			(end -0.12065 0.3048)
			(stroke
				(width 0.1)
				(type default)
			)
			(layer "F.Fab")
		)
		(fp_line
			(start -0.12065 -0.2794)
			(end 0.12065 -0.2794)
			(stroke
				(width 0.1)
				(type default)
			)
			(layer "F.Fab")
		)
		(fp_line
			(start -0.12065 -0.305054)
			(end -0.12065 -0.2794)
			(stroke
				(width 0.1)
				(type default)
			)
			(layer "F.Fab")
		)
		(fp_line
			(start -0.67945 0.3048)
			(end -0.67945 -0.305054)
			(stroke
				(width 0.1)
				(type default)
			)
			(layer "F.Fab")
		)
		(fp_line
			(start -0.67945 -0.305054)
			(end -0.12065 -0.305054)
			(stroke
				(width 0.1)
				(type default)
			)
			(layer "F.Fab")
		)
		(pad "1" smd circle
			(at -0.40005 0 180)
			(size 0 0)
			(layers "F.Cu" "F.Mask" "F.Paste")
			(net "P12V_OCP_V3_2")
		)
		(pad "2" smd circle
			(at 0.40005 0 180)
			(size 0 0)
			(layers "F.Cu" "F.Mask" "F.Paste")
			(net "P12V_OCP_AVIN_PD_2")
		)
	)
)
